(kicad_pcb
	(version 20241229)
	(generator "pcbnew")
	(generator_version "9.0")
	(general
		(thickness 1.292)
		(legacy_teardrops no)
	)
	(paper "A4")
	(title_block
		(title "LPDDR5 Testbed")
		(date "2023-12-19")
		(rev "1.0.0")
		(comment 9 "footprints 139-143 of 160")
	)
	(layers
		(0 "F.Cu" signal)
		(4 "In1.Cu" power)
		(6 "In2.Cu" power)
		(8 "In3.Cu" signal)
		(10 "In4.Cu" signal)
		(2 "B.Cu" signal)
		(9 "F.Adhes" user "F.Adhesive")
		(11 "B.Adhes" user "B.Adhesive")
		(13 "F.Paste" user)
		(15 "B.Paste" user)
		(5 "F.SilkS" user "F.Silkscreen")
		(7 "B.SilkS" user "B.Silkscreen")
		(1 "F.Mask" user)
		(3 "B.Mask" user)
		(17 "Dwgs.User" user "User.Drawings")
		(19 "Cmts.User" user "User.Comments")
		(21 "Eco1.User" user "User.Eco1")
		(23 "Eco2.User" user "User.Eco2")
		(25 "Edge.Cuts" user)
		(27 "Margin" user)
		(31 "F.CrtYd" user "F.Courtyard")
		(29 "B.CrtYd" user "B.Courtyard")
		(35 "F.Fab" user)
		(33 "B.Fab" user)
	)
	(footprint "antmicro-footprints:R_Array_4x0402_Panasonic_EXB28V"
		(layer "B.Cu")
		(at 119.35 93.8)
		(property "Reference" "R18"
			(at 0.95 1.7 0)
			(unlocked yes)
			(layer "B.SilkS")
			(effects
				(font
					(size 0.7 0.7)
					(thickness 0.15)
				)
				(justify left bottom mirror)
			)
		)
		(property "Value" "R_4x100R_0402_array"
			(at -1.5 -2 180)
			(layer "B.Fab")
			(effects
				(font
					(size 0.7 0.7)
					(thickness 0.15)
				)
				(justify left bottom mirror)
			)
		)
		(property "Author" "Antmicro"
			(at 0 0 0)
			(layer "B.Fab")
			(hide yes)
			(effects
				(font
					(size 1 1)
					(thickness 0.15)
				)
				(justify mirror)
			)
		)
		(property "License" "Apache-2.0"
			(at 0 0 0)
			(layer "B.Fab")
			(hide yes)
			(effects
				(font
					(size 1 1)
					(thickness 0.15)
				)
				(justify mirror)
			)
		)
		(property "MPN" "EXB-28V101JX"
			(at 0 0 0)
			(layer "B.Fab")
			(hide yes)
			(effects
				(font
					(size 1 1)
					(thickness 0.15)
				)
				(justify mirror)
			)
		)
		(property "Manufacturer" "Panasonic"
			(at 0 0 0)
			(layer "B.Fab")
			(hide yes)
			(effects
				(font
					(size 1 1)
					(thickness 0.15)
				)
				(justify mirror)
			)
		)
		(property "Val" "R_4x100R_0402"
			(at 0 0 0)
			(layer "B.Fab")
			(hide yes)
			(effects
				(font
					(size 1 1)
					(thickness 0.15)
				)
				(justify mirror)
			)
		)
		(sheetname "Translators")
		(sheetfile "translators.kicad_sch")
		(attr smd)
		(fp_line
			(start -1.25 0.5)
			(end -1.25 -0.498)
			(stroke
				(width 0.15)
				(type solid)
			)
			(layer "B.SilkS")
		)
		(fp_line
			(start 1.25 -0.499)
			(end 1.25 0.499)
			(stroke
				(width 0.15)
				(type solid)
			)
			(layer "B.SilkS")
		)
		(fp_rect
			(start -1.25 0.8)
			(end 1.25 -0.8)
			(stroke
				(width 0.05)
				(type solid)
			)
			(fill no)
			(layer "B.CrtYd")
		)
		(fp_line
			(start -1 -0.498)
			(end -1 0.5)
			(stroke
				(width 0.15)
				(type solid)
			)
			(layer "B.Fab")
		)
		(fp_line
			(start -1 0.5)
			(end 0.998 0.5)
			(stroke
				(width 0.15)
				(type solid)
			)
			(layer "B.Fab")
		)
		(fp_line
			(start 0.998 -0.498)
			(end -1 -0.498)
			(stroke
				(width 0.15)
				(type solid)
			)
			(layer "B.Fab")
		)
		(fp_line
			(start 0.998 0.5)
			(end 0.998 -0.498)
			(stroke
				(width 0.15)
				(type solid)
			)
			(layer "B.Fab")
		)
		(pad "1" smd roundrect
			(at -0.8875 -0.45)
			(size 0.525 0.5)
			(layers "B.Cu" "B.Mask" "B.Paste")
			(roundrect_rratio 0.25)
			(net 202 "/LPDDR5/LPDDR5_A.DQ3")
			(pinfunction "R1.1")
			(pintype "passive")
		)
		(pad "2" smd roundrect
			(at -0.25 -0.45)
			(size 0.25 0.5)
			(layers "B.Cu" "B.Mask" "B.Paste")
			(roundrect_rratio 0.25)
			(net 204 "/LPDDR5/LPDDR5_A.DQ1")
			(pinfunction "R2.1")
			(pintype "passive")
		)
		(pad "3" smd roundrect
			(at 0.25 -0.45)
			(size 0.25 0.5)
			(layers "B.Cu" "B.Mask" "B.Paste")
			(roundrect_rratio 0.25)
			(net 203 "/LPDDR5/LPDDR5_A.DQ2")
			(pinfunction "R3.1")
			(pintype "passive")
		)
		(pad "4" smd roundrect
			(at 0.8875 -0.45)
			(size 0.525 0.5)
			(layers "B.Cu" "B.Mask" "B.Paste")
			(roundrect_rratio 0.25)
			(net 205 "/LPDDR5/LPDDR5_A.DQ0")
			(pinfunction "R4.1")
			(pintype "passive")
		)
		(pad "5" smd roundrect
			(at 0.8875 0.45)
			(size 0.525 0.5)
			(layers "B.Cu" "B.Mask" "B.Paste")
			(roundrect_rratio 0.25)
			(net 14 "GND")
			(pinfunction "R4.2")
			(pintype "passive")
		)
		(pad "6" smd roundrect
			(at 0.25 0.45)
			(size 0.25 0.5)
			(layers "B.Cu" "B.Mask" "B.Paste")
			(roundrect_rratio 0.25)
			(net 14 "GND")
			(pinfunction "R3.2")
			(pintype "passive")
		)
		(pad "7" smd roundrect
			(at -0.25 0.45)
			(size 0.25 0.5)
			(layers "B.Cu" "B.Mask" "B.Paste")
			(roundrect_rratio 0.25)
			(net 14 "GND")
			(pinfunction "R2.2")
			(pintype "passive")
		)
		(pad "8" smd roundrect
			(at -0.8875 0.45)
			(size 0.525 0.5)
			(layers "B.Cu" "B.Mask" "B.Paste")
			(roundrect_rratio 0.25)
			(net 14 "GND")
			(pinfunction "R1.2")
			(pintype "passive")
		)
	)
	(footprint "antmicro-footprints:C_0402_1005Metric"
		(layer "B.Cu")
		(at 107.25 85.3)
		(descr "Capacitor SMD 0402")
		(tags "capacitor SMD 0402")
		(property "Reference" "C7"
			(at -2.55 0.5 0)
			(unlocked yes)
			(layer "B.SilkS")
			(effects
				(font
					(size 0.7 0.7)
					(thickness 0.15)
				)
				(justify right bottom mirror)
			)
		)
		(property "Value" "C_4u7_0402"
			(at -1.022927 -2.155213 0)
			(layer "B.Fab")
			(effects
				(font
					(size 0.7 0.7)
					(thickness 0.15)
				)
				(justify right bottom mirror)
			)
		)
		(property "Author" "Antmicro"
			(at 0 0 0)
			(layer "B.Fab")
			(hide yes)
			(effects
				(font
					(size 1 1)
					(thickness 0.15)
				)
				(justify mirror)
			)
		)
		(property "Dielectric" ""
			(at 0 0 0)
			(layer "B.Fab")
			(hide yes)
			(effects
				(font
					(size 1 1)
					(thickness 0.15)
				)
				(justify mirror)
			)
		)
		(property "License" "Apache-2.0"
			(at 0 0 0)
			(layer "B.Fab")
			(hide yes)
			(effects
				(font
					(size 1 1)
					(thickness 0.15)
				)
				(justify mirror)
			)
		)
		(property "MPN" "GRM155R61A475MEAAD"
			(at 0 0 0)
			(layer "B.Fab")
			(hide yes)
			(effects
				(font
					(size 1 1)
					(thickness 0.15)
				)
				(justify mirror)
			)
		)
		(property "Manufacturer" "Murata"
			(at 0 0 0)
			(layer "B.Fab")
			(hide yes)
			(effects
				(font
					(size 1 1)
					(thickness 0.15)
				)
				(justify mirror)
			)
		)
		(property "Val" "4u7"
			(at 0 0 0)
			(layer "B.Fab")
			(hide yes)
			(effects
				(font
					(size 1 1)
					(thickness 0.15)
				)
				(justify mirror)
			)
		)
		(property "Voltage" ""
			(at 0 0 0)
			(layer "B.Fab")
			(hide yes)
			(effects
				(font
					(size 1 1)
					(thickness 0.15)
				)
				(justify mirror)
			)
		)
		(sheetname "SODIMM")
		(sheetfile "sodim.kicad_sch")
		(attr smd)
		(fp_rect
			(start -0.9659 0.481258)
			(end 0.9649 -0.458742)
			(stroke
				(width 0.05)
				(type solid)
			)
			(fill no)
			(layer "B.CrtYd")
		)
		(fp_line
			(start -0.499 -0.248)
			(end -0.499 0.25)
			(stroke
				(width 0.15)
				(type solid)
			)
			(layer "B.Fab")
		)
		(fp_line
			(start -0.499 0.25)
			(end 0.499 0.25)
			(stroke
				(width 0.15)
				(type solid)
			)
			(layer "B.Fab")
		)
		(fp_line
			(start 0.499 -0.248)
			(end -0.499 -0.248)
			(stroke
				(width 0.15)
				(type solid)
			)
			(layer "B.Fab")
		)
		(fp_line
			(start 0.499 0.25)
			(end 0.499 -0.248)
			(stroke
				(width 0.15)
				(type solid)
			)
			(layer "B.Fab")
		)
		(pad "1" smd roundrect
			(at -0.484 0)
			(size 0.59 0.64)
			(layers "B.Cu" "B.Mask" "B.Paste")
			(roundrect_rratio 0.25)
			(net 14 "GND")
			(pintype "passive")
		)
		(pad "2" smd roundrect
			(at 0.484 0)
			(size 0.59 0.64)
			(layers "B.Cu" "B.Mask" "B.Paste")
			(roundrect_rratio 0.25)
			(net 35 "+1V8")
			(pintype "passive")
		)
	)
	(footprint "antmicro-footprints:C_0402_1005Metric"
		(layer "B.Cu")
		(at 134.775 82 90)
		(descr "Capacitor SMD 0402")
		(tags "capacitor SMD 0402")
		(property "Reference" "C70"
			(at -1.1 1.525 90)
			(unlocked yes)
			(layer "B.SilkS")
			(effects
				(font
					(size 0.7 0.7)
					(thickness 0.15)
				)
				(justify right bottom mirror)
			)
		)
		(property "Value" "C_4u7_0402"
			(at -1.022927 -2.155213 90)
			(layer "B.Fab")
			(effects
				(font
					(size 0.7 0.7)
					(thickness 0.15)
				)
				(justify right bottom mirror)
			)
		)
		(property "Author" "Antmicro"
			(at 216.775 -52.775 0)
			(layer "B.Fab")
			(hide yes)
			(effects
				(font
					(size 1 1)
					(thickness 0.15)
				)
				(justify mirror)
			)
		)
		(property "Dielectric" ""
			(at 216.775 -52.775 0)
			(layer "B.Fab")
			(hide yes)
			(effects
				(font
					(size 1 1)
					(thickness 0.15)
				)
				(justify mirror)
			)
		)
		(property "License" "Apache-2.0"
			(at 216.775 -52.775 0)
			(layer "B.Fab")
			(hide yes)
			(effects
				(font
					(size 1 1)
					(thickness 0.15)
				)
				(justify mirror)
			)
		)
		(property "MPN" "GRM155R61A475MEAAD"
			(at 216.775 -52.775 0)
			(layer "B.Fab")
			(hide yes)
			(effects
				(font
					(size 1 1)
					(thickness 0.15)
				)
				(justify mirror)
			)
		)
		(property "Manufacturer" "Murata"
			(at 216.775 -52.775 0)
			(layer "B.Fab")
			(hide yes)
			(effects
				(font
					(size 1 1)
					(thickness 0.15)
				)
				(justify mirror)
			)
		)
		(property "Val" "4u7"
			(at 216.775 -52.775 0)
			(layer "B.Fab")
			(hide yes)
			(effects
				(font
					(size 1 1)
					(thickness 0.15)
				)
				(justify mirror)
			)
		)
		(property "Voltage" ""
			(at 216.775 -52.775 0)
			(layer "B.Fab")
			(hide yes)
			(effects
				(font
					(size 1 1)
					(thickness 0.15)
				)
				(justify mirror)
			)
		)
		(sheetname "LPDDR5")
		(sheetfile "lpddr5.kicad_sch")
		(attr smd)
		(fp_rect
			(start -0.9659 0.481258)
			(end 0.9649 -0.458742)
			(stroke
				(width 0.05)
				(type solid)
			)
			(fill no)
			(layer "B.CrtYd")
		)
		(fp_line
			(start 0.499 -0.248)
			(end -0.499 -0.248)
			(stroke
				(width 0.15)
				(type solid)
			)
			(layer "B.Fab")
		)
		(fp_line
			(start -0.499 -0.248)
			(end -0.499 0.25)
			(stroke
				(width 0.15)
				(type solid)
			)
			(layer "B.Fab")
		)
		(fp_line
			(start 0.499 0.25)
			(end 0.499 -0.248)
			(stroke
				(width 0.15)
				(type solid)
			)
			(layer "B.Fab")
		)
		(fp_line
			(start -0.499 0.25)
			(end 0.499 0.25)
			(stroke
				(width 0.15)
				(type solid)
			)
			(layer "B.Fab")
		)
		(pad "1" smd roundrect
			(at -0.484 0 90)
			(size 0.59 0.64)
			(layers "B.Cu" "B.Mask" "B.Paste")
			(roundrect_rratio 0.25)
			(net 14 "GND")
			(pintype "passive")
		)
		(pad "2" smd roundrect
			(at 0.484 0 90)
			(size 0.59 0.64)
			(layers "B.Cu" "B.Mask" "B.Paste")
			(roundrect_rratio 0.25)
			(net 13 "+1V05")
			(pintype "passive")
		)
	)
	(footprint "antmicro-footprints:C_0402_1005Metric"
		(layer "B.Cu")
		(at 138.275 77.45)
		(descr "Capacitor SMD 0402")
		(tags "capacitor SMD 0402")
		(property "Reference" "C36"
			(at 1.525 1.35 0)
			(unlocked yes)
			(layer "B.SilkS")
			(effects
				(font
					(size 0.7 0.7)
					(thickness 0.15)
				)
				(justify right bottom mirror)
			)
		)
		(property "Value" "C_4u7_0402"
			(at -1.022927 -2.155213 0)
			(layer "B.Fab")
			(effects
				(font
					(size 0.7 0.7)
					(thickness 0.15)
				)
				(justify right bottom mirror)
			)
		)
		(property "Author" "Antmicro"
			(at 0 0 0)
			(layer "B.Fab")
			(hide yes)
			(effects
				(font
					(size 1 1)
					(thickness 0.15)
				)
				(justify mirror)
			)
		)
		(property "Dielectric" ""
			(at 0 0 0)
			(layer "B.Fab")
			(hide yes)
			(effects
				(font
					(size 1 1)
					(thickness 0.15)
				)
				(justify mirror)
			)
		)
		(property "License" "Apache-2.0"
			(at 0 0 0)
			(layer "B.Fab")
			(hide yes)
			(effects
				(font
					(size 1 1)
					(thickness 0.15)
				)
				(justify mirror)
			)
		)
		(property "MPN" "GRM155R61A475MEAAD"
			(at 0 0 0)
			(layer "B.Fab")
			(hide yes)
			(effects
				(font
					(size 1 1)
					(thickness 0.15)
				)
				(justify mirror)
			)
		)
		(property "Manufacturer" "Murata"
			(at 0 0 0)
			(layer "B.Fab")
			(hide yes)
			(effects
				(font
					(size 1 1)
					(thickness 0.15)
				)
				(justify mirror)
			)
		)
		(property "Val" "4u7"
			(at 0 0 0)
			(layer "B.Fab")
			(hide yes)
			(effects
				(font
					(size 1 1)
					(thickness 0.15)
				)
				(justify mirror)
			)
		)
		(property "Voltage" ""
			(at 0 0 0)
			(layer "B.Fab")
			(hide yes)
			(effects
				(font
					(size 1 1)
					(thickness 0.15)
				)
				(justify mirror)
			)
		)
		(sheetname "LPDDR5")
		(sheetfile "lpddr5.kicad_sch")
		(attr smd)
		(fp_rect
			(start -0.9659 0.481258)
			(end 0.9649 -0.458742)
			(stroke
				(width 0.05)
				(type solid)
			)
			(fill no)
			(layer "B.CrtYd")
		)
		(fp_line
			(start -0.499 -0.248)
			(end -0.499 0.25)
			(stroke
				(width 0.15)
				(type solid)
			)
			(layer "B.Fab")
		)
		(fp_line
			(start -0.499 0.25)
			(end 0.499 0.25)
			(stroke
				(width 0.15)
				(type solid)
			)
			(layer "B.Fab")
		)
		(fp_line
			(start 0.499 -0.248)
			(end -0.499 -0.248)
			(stroke
				(width 0.15)
				(type solid)
			)
			(layer "B.Fab")
		)
		(fp_line
			(start 0.499 0.25)
			(end 0.499 -0.248)
			(stroke
				(width 0.15)
				(type solid)
			)
			(layer "B.Fab")
		)
		(pad "1" smd roundrect
			(at -0.484 0)
			(size 0.59 0.64)
			(layers "B.Cu" "B.Mask" "B.Paste")
			(roundrect_rratio 0.25)
			(net 14 "GND")
			(pintype "passive")
		)
		(pad "2" smd roundrect
			(at 0.484 0)
			(size 0.59 0.64)
			(layers "B.Cu" "B.Mask" "B.Paste")
			(roundrect_rratio 0.25)
			(net 4 "+0V5")
			(pintype "passive")
		)
	)
	(footprint "antmicro-footprints:C_0402_1005Metric"
		(layer "B.Cu")
		(at 133.375 75.55 90)
		(descr "Capacitor SMD 0402")
		(tags "capacitor SMD 0402")
		(property "Reference" "C55"
			(at 1.25 0.699 90)
			(unlocked yes)
			(layer "B.SilkS")
			(effects
				(font
					(size 0.7 0.7)
					(thickness 0.15)
				)
				(justify right bottom mirror)
			)
		)
		(property "Value" "C_4u7_0402"
			(at -1.022927 -2.155213 90)
			(layer "B.Fab")
			(effects
				(font
					(size 0.7 0.7)
					(thickness 0.15)
				)
				(justify right bottom mirror)
			)
		)
		(property "Author" "Antmicro"
			(at 208.925 -57.825 0)
			(layer "B.Fab")
			(hide yes)
			(effects
				(font
					(size 1 1)
					(thickness 0.15)
				)
				(justify mirror)
			)
		)
		(property "Dielectric" ""
			(at 208.925 -57.825 0)
			(layer "B.Fab")
			(hide yes)
			(effects
				(font
					(size 1 1)
					(thickness 0.15)
				)
				(justify mirror)
			)
		)
		(property "License" "Apache-2.0"
			(at 208.925 -57.825 0)
			(layer "B.Fab")
			(hide yes)
			(effects
				(font
					(size 1 1)
					(thickness 0.15)
				)
				(justify mirror)
			)
		)
		(property "MPN" "GRM155R61A475MEAAD"
			(at 208.925 -57.825 0)
			(layer "B.Fab")
			(hide yes)
			(effects
				(font
					(size 1 1)
					(thickness 0.15)
				)
				(justify mirror)
			)
		)
		(property "Manufacturer" "Murata"
			(at 208.925 -57.825 0)
			(layer "B.Fab")
			(hide yes)
			(effects
				(font
					(size 1 1)
					(thickness 0.15)
				)
				(justify mirror)
			)
		)
		(property "Val" "4u7"
			(at 208.925 -57.825 0)
			(layer "B.Fab")
			(hide yes)
			(effects
				(font
					(size 1 1)
					(thickness 0.15)
				)
				(justify mirror)
			)
		)
		(property "Voltage" ""
			(at 208.925 -57.825 0)
			(layer "B.Fab")
			(hide yes)
			(effects
				(font
					(size 1 1)
					(thickness 0.15)
				)
				(justify mirror)
			)
		)
		(sheetname "LPDDR5")
		(sheetfile "lpddr5.kicad_sch")
		(attr smd)
		(fp_rect
			(start -0.9659 0.481258)
			(end 0.9649 -0.458742)
			(stroke
				(width 0.05)
				(type solid)
			)
			(fill no)
			(layer "B.CrtYd")
		)
		(fp_line
			(start 0.499 -0.248)
			(end -0.499 -0.248)
			(stroke
				(width 0.15)
				(type solid)
			)
			(layer "B.Fab")
		)
		(fp_line
			(start -0.499 -0.248)
			(end -0.499 0.25)
			(stroke
				(width 0.15)
				(type solid)
			)
			(layer "B.Fab")
		)
		(fp_line
			(start 0.499 0.25)
			(end 0.499 -0.248)
			(stroke
				(width 0.15)
				(type solid)
			)
			(layer "B.Fab")
		)
		(fp_line
			(start -0.499 0.25)
			(end 0.499 0.25)
			(stroke
				(width 0.15)
				(type solid)
			)
			(layer "B.Fab")
		)
		(pad "1" smd roundrect
			(at -0.484 0 90)
			(size 0.59 0.64)
			(layers "B.Cu" "B.Mask" "B.Paste")
			(roundrect_rratio 0.25)
			(net 14 "GND")
			(pintype "passive")
		)
		(pad "2" smd roundrect
			(at 0.484 0 90)
			(size 0.59 0.64)
			(layers "B.Cu" "B.Mask" "B.Paste")
			(roundrect_rratio 0.25)
			(net 12 "+0V9")
			(pintype "passive")
		)
	)
)
